(kicad_pcb
	(version 20260206)
	(generator "pcbnew")
	(generator_version "10.0")
	(general
		(thickness 1.6)
		(legacy_teardrops no)
	)
	(paper "A4")
	(title_block
		(title "peb — Lightning_PEB_BRD.brd")
		(comment 1 "Lightning (Wiwynn / Facebook NVMe JBOF) / footprints 981-987 of 2563")
	)
	(layers
		(0 "F.Cu" signal "TOP")
		(4 "In1.Cu" signal "L2GND")
		(6 "In2.Cu" signal "L3")
		(8 "In3.Cu" signal "L4VCC")
		(10 "In4.Cu" signal "L5VCC")
		(12 "In5.Cu" signal "L6")
		(14 "In6.Cu" signal "L7GND")
		(2 "B.Cu" signal "BOTTOM")
		(9 "F.Adhes" user "F.Adhesive")
		(11 "B.Adhes" user "B.Adhesive")
		(13 "F.Paste" user "Package Geometry/Pastemask Top")
		(15 "B.Paste" user "Package Geometry/Pastemask Bottom")
		(5 "F.SilkS" user "Ref Des/Silkscreen Top")
		(7 "B.SilkS" user "Ref Des/Silkscreen Bottom")
		(1 "F.Mask" user "Board Geometry/Soldermask Top")
		(3 "B.Mask" user "Board Geometry/Soldermask Bottom")
		(17 "Dwgs.User" user "User.Drawings")
		(19 "Cmts.User" user "User.Comments")
		(21 "Eco1.User" user "User.Eco1")
		(23 "Eco2.User" user "User.Eco2")
		(25 "Edge.Cuts" user "Board Geometry/Outline")
		(27 "Margin" user)
		(31 "F.CrtYd" user "Package Geometry/Place Bound Top")
		(29 "B.CrtYd" user "Package Geometry/Place Bound Bottom")
		(35 "F.Fab" user "Ref Des/Assembly Top")
		(33 "B.Fab" user "Ref Des/Assembly Bottom")
	)
	(footprint ""
		(layer "F.Cu")
		(at 254.173482 -12.0523)
		(property "Reference" "R12"
			(at 0 0 0)
			(layer "F.SilkS")
			(hide yes)
			(effects
				(font
					(size 1.27 1.27)
				)
			)
		)
		(property "Value" "0R2J-2-GP"
			(at 0.064008 -3.993896 0)
			(unlocked yes)
			(layer "F.Fab")
			(hide yes)
			(effects
				(font
					(size 1.016 1.016)
					(thickness 0.1524)
				)
			)
		)
		(property "Device Type" "R402H16"
			(at 0.064008 -5.517896 0)
			(unlocked yes)
			(layer "F.Fab")
			(hide yes)
			(effects
				(font
					(size 1.016 1.016)
					(thickness 0.1524)
				)
			)
		)
		(duplicate_pad_numbers_are_jumpers no)
		(fp_line
			(start -0.508 -0.9398)
			(end -0.508 0.9398)
			(stroke
				(width 0.1524)
				(type default)
			)
			(layer "F.SilkS")
		)
		(fp_line
			(start 0.508 -0.9398)
			(end -0.508 -0.9398)
			(stroke
				(width 0.1524)
				(type default)
			)
			(layer "F.SilkS")
		)
		(fp_rect
			(start -0.508 0.9398)
			(end 0.508 -0.9398)
			(stroke
				(width 0)
				(type default)
			)
			(fill no)
			(layer "F.CrtYd")
		)
		(fp_rect
			(start -0.508 0.9398)
			(end 0.508 -0.9398)
			(stroke
				(width 0)
				(type default)
			)
			(fill no)
			(layer "F.Fab")
		)
		(pad "1" smd custom
			(at 0 -0.4445)
			(size 0.1397 0.1397)
			(layers "F.Cu" "F.Mask" "F.Paste")
			(net "THERM_BASE")
			(options
				(clearance outline)
				(anchor circle)
			)
			(primitives
				(gr_poly
					(pts
						(arc
							(start -0.1778 -0.2794)
							(mid -0.249642 -0.249642)
							(end -0.2794 -0.1778)
						)
						(arc
							(start -0.2794 0.1778)
							(mid -0.249642 0.249642)
							(end -0.1778 0.2794)
						)
						(arc
							(start 0.1778 0.2794)
							(mid 0.249642 0.249642)
							(end 0.2794 0.1778)
						)
						(arc
							(start 0.2794 -0.1778)
							(mid 0.249642 -0.249642)
							(end 0.1778 -0.2794)
						)
					)
					(width 0)
					(fill yes)
				)
			)
		)
		(pad "2" smd custom
			(at 0 0.4445)
			(size 0.1397 0.1397)
			(layers "F.Cu" "F.Mask" "F.Paste")
			(net "THERM_BASE_R")
			(options
				(clearance outline)
				(anchor circle)
			)
			(primitives
				(gr_poly
					(pts
						(arc
							(start -0.1778 -0.2794)
							(mid -0.249642 -0.249642)
							(end -0.2794 -0.1778)
						)
						(arc
							(start -0.2794 0.1778)
							(mid -0.249642 0.249642)
							(end -0.1778 0.2794)
						)
						(arc
							(start 0.1778 0.2794)
							(mid 0.249642 0.249642)
							(end 0.2794 0.1778)
						)
						(arc
							(start 0.2794 -0.1778)
							(mid 0.249642 -0.249642)
							(end 0.1778 -0.2794)
						)
					)
					(width 0)
					(fill yes)
				)
			)
		)
	)
	(footprint ""
		(layer "F.Cu")
		(at 188.849 -11.303 90)
		(property "Reference" "Q13"
			(at 0 0 90)
			(layer "F.SilkS")
			(hide yes)
			(effects
				(font
					(size 1.27 1.27)
				)
			)
		)
		(property "Value" "2N7002K-1-GP"
			(at 0.127 -8.9662 90)
			(unlocked yes)
			(layer "F.Fab")
			(hide yes)
			(effects
				(font
					(size 1.016 1.016)
					(thickness 0.1524)
				)
			)
		)
		(property "Device Type" "SOT23DGS2D4H44"
			(at 0.127 -10.4902 90)
			(unlocked yes)
			(layer "F.Fab")
			(hide yes)
			(effects
				(font
					(size 1.016 1.016)
					(thickness 0.1524)
				)
			)
		)
		(duplicate_pad_numbers_are_jumpers no)
		(fp_line
			(start 1.651 -1.778)
			(end -1.651 -1.778)
			(stroke
				(width 0.1524)
				(type default)
			)
			(layer "F.SilkS")
		)
		(fp_line
			(start -1.651 -1.778)
			(end -1.651 1.778)
			(stroke
				(width 0.1524)
				(type default)
			)
			(layer "F.SilkS")
		)
		(fp_line
			(start 1.651 1.778)
			(end 1.651 -1.778)
			(stroke
				(width 0.1524)
				(type default)
			)
			(layer "F.SilkS")
		)
		(fp_line
			(start -1.651 1.778)
			(end 1.651 1.778)
			(stroke
				(width 0.1524)
				(type default)
			)
			(layer "F.SilkS")
		)
		(fp_poly
			(pts
				(xy -1.778 1.8796) (xy -1.778 -1.8796) (xy 1.778 -1.8796) (xy 1.778 1.8796)
			)
			(stroke
				(width 0)
				(type default)
			)
			(fill no)
			(layer "F.CrtYd")
		)
		(fp_poly
			(pts
				(xy -1.778 1.8796) (xy -1.778 -1.8796) (xy 1.778 -1.8796) (xy 1.778 1.8796)
			)
			(stroke
				(width 0)
				(type default)
			)
			(fill no)
			(layer "F.Fab")
		)
		(pad "D" smd custom
			(at 0 -0.9525 90)
			(size 0.1905 0.1905)
			(layers "F.Cu" "F.Mask" "F.Paste")
			(net "ENCLO_LED_RED")
			(options
				(clearance outline)
				(anchor circle)
			)
			(primitives
				(gr_poly
					(pts
						(arc
							(start -0.1778 0.5715)
							(mid -0.321484 0.511984)
							(end -0.381 0.3683)
						)
						(arc
							(start -0.381 -0.3683)
							(mid -0.321484 -0.511984)
							(end -0.1778 -0.5715)
						)
						(arc
							(start 0.1778 -0.5715)
							(mid 0.321484 -0.511984)
							(end 0.381 -0.3683)
						)
						(arc
							(start 0.381 0.3683)
							(mid 0.321484 0.511984)
							(end 0.1778 0.5715)
						)
					)
					(width 0)
					(fill yes)
				)
			)
		)
		(pad "G" smd custom
			(at -0.98425 0.9525 90)
			(size 0.1905 0.1905)
			(layers "F.Cu" "F.Mask" "F.Paste")
			(net "ENCLO_LED_RED_D")
			(options
				(clearance outline)
				(anchor circle)
			)
			(primitives
				(gr_poly
					(pts
						(arc
							(start -0.1778 0.5715)
							(mid -0.321484 0.511984)
							(end -0.381 0.3683)
						)
						(arc
							(start -0.381 -0.3683)
							(mid -0.321484 -0.511984)
							(end -0.1778 -0.5715)
						)
						(arc
							(start 0.1778 -0.5715)
							(mid 0.321484 -0.511984)
							(end 0.381 -0.3683)
						)
						(arc
							(start 0.381 0.3683)
							(mid 0.321484 0.511984)
							(end 0.1778 0.5715)
						)
					)
					(width 0)
					(fill yes)
				)
			)
		)
		(pad "S" smd custom
			(at 0.98425 0.9525 90)
			(size 0.1905 0.1905)
			(layers "F.Cu" "F.Mask" "F.Paste")
			(net "GND")
			(options
				(clearance outline)
				(anchor circle)
			)
			(primitives
				(gr_poly
					(pts
						(arc
							(start -0.1778 0.5715)
							(mid -0.321484 0.511984)
							(end -0.381 0.3683)
						)
						(arc
							(start -0.381 -0.3683)
							(mid -0.321484 -0.511984)
							(end -0.1778 -0.5715)
						)
						(arc
							(start 0.1778 -0.5715)
							(mid 0.321484 -0.511984)
							(end 0.381 -0.3683)
						)
						(arc
							(start 0.381 0.3683)
							(mid 0.321484 0.511984)
							(end 0.1778 0.5715)
						)
					)
					(width 0)
					(fill yes)
				)
			)
		)
	)
	(footprint ""
		(layer "F.Cu")
		(at 332.994 -71.247)
		(property "Reference" "PR151"
			(at 0 0 0)
			(layer "F.SilkS")
			(hide yes)
			(effects
				(font
					(size 1.27 1.27)
				)
			)
		)
		(property "Value" "100KR2F-L1-GP"
			(at 0.064008 -3.993896 0)
			(unlocked yes)
			(layer "F.Fab")
			(hide yes)
			(effects
				(font
					(size 1.016 1.016)
					(thickness 0.1524)
				)
			)
		)
		(property "Device Type" "R402H16"
			(at 0.064008 -5.517896 0)
			(unlocked yes)
			(layer "F.Fab")
			(hide yes)
			(effects
				(font
					(size 1.016 1.016)
					(thickness 0.1524)
				)
			)
		)
		(duplicate_pad_numbers_are_jumpers no)
		(fp_line
			(start -0.508 -0.9398)
			(end -0.508 0.9398)
			(stroke
				(width 0.1524)
				(type default)
			)
			(layer "F.SilkS")
		)
		(fp_line
			(start 0.508 -0.9398)
			(end -0.508 -0.9398)
			(stroke
				(width 0.1524)
				(type default)
			)
			(layer "F.SilkS")
		)
		(fp_rect
			(start -0.508 0.9398)
			(end 0.508 -0.9398)
			(stroke
				(width 0)
				(type default)
			)
			(fill no)
			(layer "F.CrtYd")
		)
		(fp_rect
			(start -0.508 0.9398)
			(end 0.508 -0.9398)
			(stroke
				(width 0)
				(type default)
			)
			(fill no)
			(layer "F.Fab")
		)
		(pad "1" smd custom
			(at 0 -0.4445)
			(size 0.1397 0.1397)
			(layers "F.Cu" "F.Mask" "F.Paste")
			(net "P12V")
			(options
				(clearance outline)
				(anchor circle)
			)
			(primitives
				(gr_poly
					(pts
						(arc
							(start -0.1778 -0.2794)
							(mid -0.249642 -0.249642)
							(end -0.2794 -0.1778)
						)
						(arc
							(start -0.2794 0.1778)
							(mid -0.249642 0.249642)
							(end -0.1778 0.2794)
						)
						(arc
							(start 0.1778 0.2794)
							(mid 0.249642 0.249642)
							(end 0.2794 0.1778)
						)
						(arc
							(start 0.2794 -0.1778)
							(mid 0.249642 -0.249642)
							(end 0.1778 -0.2794)
						)
					)
					(width 0)
					(fill yes)
				)
			)
		)
		(pad "2" smd custom
			(at 0 0.4445)
			(size 0.1397 0.1397)
			(layers "F.Cu" "F.Mask" "F.Paste")
			(net "P0V9_E_EN")
			(options
				(clearance outline)
				(anchor circle)
			)
			(primitives
				(gr_poly
					(pts
						(arc
							(start -0.1778 -0.2794)
							(mid -0.249642 -0.249642)
							(end -0.2794 -0.1778)
						)
						(arc
							(start -0.2794 0.1778)
							(mid -0.249642 0.249642)
							(end -0.1778 0.2794)
						)
						(arc
							(start 0.1778 0.2794)
							(mid 0.249642 0.249642)
							(end 0.2794 0.1778)
						)
						(arc
							(start 0.2794 -0.1778)
							(mid 0.249642 -0.249642)
							(end 0.1778 -0.2794)
						)
					)
					(width 0)
					(fill yes)
				)
			)
		)
	)
	(footprint ""
		(layer "F.Cu")
		(at 25.419304 -109.83722)
		(property "Reference" "R9044"
			(at 0 0 0)
			(layer "F.SilkS")
			(hide yes)
			(effects
				(font
					(size 1.27 1.27)
				)
			)
		)
		(property "Value" "470R2F-GP"
			(at 0.064008 -3.993896 0)
			(unlocked yes)
			(layer "F.Fab")
			(hide yes)
			(effects
				(font
					(size 1.016 1.016)
					(thickness 0.1524)
				)
			)
		)
		(property "Device Type" "R402H16"
			(at 0.064008 -5.517896 0)
			(unlocked yes)
			(layer "F.Fab")
			(hide yes)
			(effects
				(font
					(size 1.016 1.016)
					(thickness 0.1524)
				)
			)
		)
		(duplicate_pad_numbers_are_jumpers no)
		(fp_line
			(start -0.508 -0.9398)
			(end -0.508 0.9398)
			(stroke
				(width 0.1524)
				(type default)
			)
			(layer "F.SilkS")
		)
		(fp_line
			(start 0.508 -0.9398)
			(end -0.508 -0.9398)
			(stroke
				(width 0.1524)
				(type default)
			)
			(layer "F.SilkS")
		)
		(fp_rect
			(start -0.508 0.9398)
			(end 0.508 -0.9398)
			(stroke
				(width 0)
				(type default)
			)
			(fill no)
			(layer "F.CrtYd")
		)
		(fp_rect
			(start -0.508 0.9398)
			(end 0.508 -0.9398)
			(stroke
				(width 0)
				(type default)
			)
			(fill no)
			(layer "F.Fab")
		)
		(pad "1" smd custom
			(at 0 -0.4445)
			(size 0.1397 0.1397)
			(layers "F.Cu" "F.Mask" "F.Paste")
			(net "P3V3_STBY")
			(options
				(clearance outline)
				(anchor circle)
			)
			(primitives
				(gr_poly
					(pts
						(arc
							(start -0.1778 -0.2794)
							(mid -0.249642 -0.249642)
							(end -0.2794 -0.1778)
						)
						(arc
							(start -0.2794 0.1778)
							(mid -0.249642 0.249642)
							(end -0.1778 0.2794)
						)
						(arc
							(start 0.1778 0.2794)
							(mid 0.249642 0.249642)
							(end 0.2794 0.1778)
						)
						(arc
							(start 0.2794 -0.1778)
							(mid 0.249642 -0.249642)
							(end 0.1778 -0.2794)
						)
					)
					(width 0)
					(fill yes)
				)
			)
		)
		(pad "2" smd custom
			(at 0 0.4445)
			(size 0.1397 0.1397)
			(layers "F.Cu" "F.Mask" "F.Paste")
			(net "BMC_REFCLK_P")
			(options
				(clearance outline)
				(anchor circle)
			)
			(primitives
				(gr_poly
					(pts
						(arc
							(start -0.1778 -0.2794)
							(mid -0.249642 -0.249642)
							(end -0.2794 -0.1778)
						)
						(arc
							(start -0.2794 0.1778)
							(mid -0.249642 0.249642)
							(end -0.1778 0.2794)
						)
						(arc
							(start 0.1778 0.2794)
							(mid 0.249642 0.249642)
							(end 0.2794 0.1778)
						)
						(arc
							(start 0.2794 -0.1778)
							(mid 0.249642 -0.249642)
							(end 0.1778 -0.2794)
						)
					)
					(width 0)
					(fill yes)
				)
			)
		)
	)
	(footprint ""
		(layer "F.Cu")
		(at 64.135 -47.681388 90)
		(property "Reference" "PC32"
			(at 0 0 90)
			(layer "F.SilkS")
			(hide yes)
			(effects
				(font
					(size 1.27 1.27)
				)
			)
		)
		(property "Value" "SC10U25V5KX-GP"
			(at -0.0762 -6.1214 90)
			(unlocked yes)
			(layer "F.Fab")
			(hide yes)
			(effects
				(font
					(size 1.016 1.016)
					(thickness 0.1524)
				)
			)
		)
		(property "Device Type" "C805H56"
			(at -0.0762 -8.1534 90)
			(unlocked yes)
			(layer "F.Fab")
			(hide yes)
			(effects
				(font
					(size 1.016 1.016)
					(thickness 0.1524)
				)
			)
		)
		(duplicate_pad_numbers_are_jumpers no)
		(fp_line
			(start 0.635 0)
			(end -0.635 0)
			(stroke
				(width 0.508)
				(type default)
			)
			(layer "F.SilkS")
		)
		(fp_rect
			(start -0.9652 1.778)
			(end 0.9652 -1.778)
			(stroke
				(width 0)
				(type default)
			)
			(fill no)
			(layer "F.CrtYd")
		)
		(fp_poly
			(pts
				(xy -0.9652 -1.778) (xy 0.9652 -1.778) (xy 0.9652 1.778) (xy -0.9652 1.778)
			)
			(stroke
				(width 0)
				(type default)
			)
			(fill no)
			(layer "F.Fab")
		)
		(pad "1" smd rect
			(at 0 -0.9652 90)
			(size 1.397 1.143)
			(layers "F.Cu" "F.Mask" "F.Paste")
			(net "P3V3_STBY_VIN")
		)
		(pad "2" smd rect
			(at 0 0.9652 90)
			(size 1.397 1.143)
			(layers "F.Cu" "F.Mask" "F.Paste")
			(net "GND")
		)
	)
	(footprint ""
		(layer "F.Cu")
		(at 324.485 -99.568 180)
		(property "Reference" "R7990"
			(at 0 0 180)
			(layer "F.SilkS")
			(hide yes)
			(effects
				(font
					(size 1.27 1.27)
				)
			)
		)
		(property "Value" "0R2J-2-GP"
			(at 0.064008 -3.993896 180)
			(unlocked yes)
			(layer "F.Fab")
			(hide yes)
			(effects
				(font
					(size 1.016 1.016)
					(thickness 0.1524)
				)
			)
		)
		(property "Device Type" "R402H16"
			(at 0.064008 -5.517896 180)
			(unlocked yes)
			(layer "F.Fab")
			(hide yes)
			(effects
				(font
					(size 1.016 1.016)
					(thickness 0.1524)
				)
			)
		)
		(duplicate_pad_numbers_are_jumpers no)
		(fp_line
			(start 0.508 -0.9398)
			(end -0.508 -0.9398)
			(stroke
				(width 0.1524)
				(type default)
			)
			(layer "F.SilkS")
		)
		(fp_line
			(start -0.508 -0.9398)
			(end -0.508 0.9398)
			(stroke
				(width 0.1524)
				(type default)
			)
			(layer "F.SilkS")
		)
		(fp_rect
			(start -0.508 0.9398)
			(end 0.508 -0.9398)
			(stroke
				(width 0)
				(type default)
			)
			(fill no)
			(layer "F.CrtYd")
		)
		(fp_rect
			(start -0.508 0.9398)
			(end 0.508 -0.9398)
			(stroke
				(width 0)
				(type default)
			)
			(fill no)
			(layer "F.Fab")
		)
		(pad "1" smd custom
			(at 0 -0.4445 180)
			(size 0.1397 0.1397)
			(layers "F.Cu" "F.Mask" "F.Paste")
			(net "IOEXP_PEWAKE#")
			(options
				(clearance outline)
				(anchor circle)
			)
			(primitives
				(gr_poly
					(pts
						(arc
							(start -0.1778 -0.2794)
							(mid -0.249642 -0.249642)
							(end -0.2794 -0.1778)
						)
						(arc
							(start -0.2794 0.1778)
							(mid -0.249642 0.249642)
							(end -0.1778 0.2794)
						)
						(arc
							(start 0.1778 0.2794)
							(mid 0.249642 0.249642)
							(end 0.2794 0.1778)
						)
						(arc
							(start 0.2794 -0.1778)
							(mid 0.249642 -0.249642)
							(end 0.1778 -0.2794)
						)
					)
					(width 0)
					(fill yes)
				)
			)
		)
		(pad "2" smd custom
			(at 0 0.4445 180)
			(size 0.1397 0.1397)
			(layers "F.Cu" "F.Mask" "F.Paste")
			(net "PEWAKE#")
			(options
				(clearance outline)
				(anchor circle)
			)
			(primitives
				(gr_poly
					(pts
						(arc
							(start -0.1778 -0.2794)
							(mid -0.249642 -0.249642)
							(end -0.2794 -0.1778)
						)
						(arc
							(start -0.2794 0.1778)
							(mid -0.249642 0.249642)
							(end -0.1778 0.2794)
						)
						(arc
							(start 0.1778 0.2794)
							(mid 0.249642 0.249642)
							(end 0.2794 0.1778)
						)
						(arc
							(start 0.2794 -0.1778)
							(mid 0.249642 -0.249642)
							(end 0.1778 -0.2794)
						)
					)
					(width 0)
					(fill yes)
				)
			)
		)
	)
	(footprint ""
		(layer "F.Cu")
		(at 127.992124 -196.443092)
		(property "Reference" "R7953"
			(at 0 0 0)
			(layer "F.SilkS")
			(hide yes)
			(effects
				(font
					(size 1.27 1.27)
				)
			)
		)
		(property "Value" "0R2J-2-GP"
			(at 0.064008 -3.993896 0)
			(unlocked yes)
			(layer "F.Fab")
			(hide yes)
			(effects
				(font
					(size 1.016 1.016)
					(thickness 0.1524)
				)
			)
		)
		(property "Device Type" "R402H16"
			(at 0.064008 -5.517896 0)
			(unlocked yes)
			(layer "F.Fab")
			(hide yes)
			(effects
				(font
					(size 1.016 1.016)
					(thickness 0.1524)
				)
			)
		)
		(duplicate_pad_numbers_are_jumpers no)
		(fp_line
			(start -0.508 -0.9398)
			(end -0.508 0.9398)
			(stroke
				(width 0.1524)
				(type default)
			)
			(layer "F.SilkS")
		)
		(fp_line
			(start 0.508 -0.9398)
			(end -0.508 -0.9398)
			(stroke
				(width 0.1524)
				(type default)
			)
			(layer "F.SilkS")
		)
		(fp_rect
			(start -0.508 0.9398)
			(end 0.508 -0.9398)
			(stroke
				(width 0)
				(type default)
			)
			(fill no)
			(layer "F.CrtYd")
		)
		(fp_rect
			(start -0.508 0.9398)
			(end 0.508 -0.9398)
			(stroke
				(width 0)
				(type default)
			)
			(fill no)
			(layer "F.Fab")
		)
		(pad "1" smd custom
			(at 0 -0.4445)
			(size 0.1397 0.1397)
			(layers "F.Cu" "F.Mask" "F.Paste")
			(net "SSD_PWREN1")
			(options
				(clearance outline)
				(anchor circle)
			)
			(primitives
				(gr_poly
					(pts
						(arc
							(start -0.1778 -0.2794)
							(mid -0.249642 -0.249642)
							(end -0.2794 -0.1778)
						)
						(arc
							(start -0.2794 0.1778)
							(mid -0.249642 0.249642)
							(end -0.1778 0.2794)
						)
						(arc
							(start 0.1778 0.2794)
							(mid 0.249642 0.249642)
							(end 0.2794 0.1778)
						)
						(arc
							(start 0.2794 -0.1778)
							(mid 0.249642 -0.249642)
							(end 0.1778 -0.2794)
						)
					)
					(width 0)
					(fill yes)
				)
			)
		)
		(pad "2" smd custom
			(at 0 0.4445)
			(size 0.1397 0.1397)
			(layers "F.Cu" "F.Mask" "F.Paste")
			(net "SSD_PWREN1_R")
			(options
				(clearance outline)
				(anchor circle)
			)
			(primitives
				(gr_poly
					(pts
						(arc
							(start -0.1778 -0.2794)
							(mid -0.249642 -0.249642)
							(end -0.2794 -0.1778)
						)
						(arc
							(start -0.2794 0.1778)
							(mid -0.249642 0.249642)
							(end -0.1778 0.2794)
						)
						(arc
							(start 0.1778 0.2794)
							(mid 0.249642 0.249642)
							(end 0.2794 0.1778)
						)
						(arc
							(start 0.2794 -0.1778)
							(mid 0.249642 -0.249642)
							(end 0.1778 -0.2794)
						)
					)
					(width 0)
					(fill yes)
				)
			)
		)
	)
)
